(kicad_pcb
	(version 20260206)
	(generator "pcbnew")
	(generator_version "10.0")
	(general
		(thickness 1.6)
		(legacy_teardrops no)
	)
	(paper "A4")
	(title_block
		(title "01162023_DA0F0TEBIF0_F0T_Expander_BD_F_brd_V02_OCP.brd")
		(comment 1 "Grand Teton / footprints 8641-8649 of 9728")
	)
	(layers
		(0 "F.Cu" signal "TOP")
		(4 "In1.Cu" signal "GND")
		(6 "In2.Cu" signal "VCC")
		(8 "In3.Cu" signal "VCC1")
		(10 "In4.Cu" signal "GND1")
		(12 "In5.Cu" signal "IN1")
		(14 "In6.Cu" signal "GND2")
		(16 "In7.Cu" signal "IN2")
		(18 "In8.Cu" signal "GND3")
		(20 "In9.Cu" signal "IN3")
		(22 "In10.Cu" signal "GND4")
		(24 "In11.Cu" signal "IN4")
		(26 "In12.Cu" signal "GND5")
		(28 "In13.Cu" signal "IN5")
		(30 "In14.Cu" signal "GND6")
		(32 "In15.Cu" signal "IN6")
		(34 "In16.Cu" signal "GND7")
		(2 "B.Cu" signal "BOTTOM")
		(9 "F.Adhes" user "F.Adhesive")
		(11 "B.Adhes" user "B.Adhesive")
		(13 "F.Paste" user "Package Geometry/Pastemask Top")
		(15 "B.Paste" user "Package Geometry/Pastemask Bottom")
		(5 "F.SilkS" user "Ref Des/Silkscreen Top")
		(7 "B.SilkS" user "Ref Des/Silkscreen Bottom")
		(1 "F.Mask" user "Board Geometry/Soldermask Top")
		(3 "B.Mask" user "Board Geometry/Soldermask Bottom")
		(17 "Dwgs.User" user "User.Drawings")
		(19 "Cmts.User" user "User.Comments")
		(21 "Eco1.User" user "User.Eco1")
		(23 "Eco2.User" user "User.Eco2")
		(25 "Edge.Cuts" user "Board Geometry/Outline")
		(27 "Margin" user)
		(31 "F.CrtYd" user "Package Geometry/Place Bound Top")
		(29 "B.CrtYd" user "Package Geometry/Place Bound Bottom")
		(35 "F.Fab" user "Ref Des/Assembly Top")
		(33 "B.Fab" user "Ref Des/Assembly Bottom")
	)
	(footprint ""
		(layer "B.Cu")
		(at 361.98048 -284.796738 -90)
		(property "Reference" "PC193"
			(at 0 0 90)
			(layer "B.SilkS")
			(hide yes)
			(effects
				(font
					(size 1.27 1.27)
				)
				(justify mirror)
			)
		)
		(property "Value" ""
			(at 0 0 90)
			(layer "B.Fab")
			(effects
				(font
					(size 1.27 1.27)
				)
				(justify mirror)
			)
		)
		(duplicate_pad_numbers_are_jumpers no)
		(fp_line
			(start -1.524 0.762)
			(end 1.524 0.762)
			(stroke
				(width 0.1524)
				(type default)
			)
			(layer "B.SilkS")
		)
		(fp_line
			(start 1.524 0.762)
			(end 1.524 -0.762)
			(stroke
				(width 0.1524)
				(type default)
			)
			(layer "B.SilkS")
		)
		(fp_line
			(start -1.524 -0.762)
			(end -1.524 0.762)
			(stroke
				(width 0.1524)
				(type default)
			)
			(layer "B.SilkS")
		)
		(fp_line
			(start 1.524 -0.762)
			(end -1.524 -0.762)
			(stroke
				(width 0.1524)
				(type default)
			)
			(layer "B.SilkS")
		)
		(fp_line
			(start -1.1049 0.724916)
			(end -1.1049 -0.724916)
			(stroke
				(width 0.1)
				(type default)
			)
			(layer "B.Fab")
		)
		(fp_line
			(start 1.1049 0.724916)
			(end -1.1049 0.724916)
			(stroke
				(width 0.1)
				(type default)
			)
			(layer "B.Fab")
		)
		(fp_line
			(start -1.1049 -0.724916)
			(end 1.1049 -0.724916)
			(stroke
				(width 0.1)
				(type default)
			)
			(layer "B.Fab")
		)
		(fp_line
			(start 1.1049 -0.724916)
			(end 1.1049 0.724916)
			(stroke
				(width 0.1)
				(type default)
			)
			(layer "B.Fab")
		)
		(pad "1" smd rect
			(at 0.889 0 270)
			(size 1.016 1.27)
			(layers "B.Cu" "B.Mask" "B.Paste")
			(net "SW_P12V_P0V8_PEX3_FLT")
		)
		(pad "2" smd rect
			(at -0.889 0 270)
			(size 1.016 1.27)
			(layers "B.Cu" "B.Mask" "B.Paste")
			(net "GND")
		)
	)
	(footprint ""
		(layer "B.Cu")
		(at 171.474892 -305.399948 -90)
		(property "Reference" "C3136"
			(at 0 0 90)
			(layer "B.SilkS")
			(hide yes)
			(effects
				(font
					(size 1.27 1.27)
				)
				(justify mirror)
			)
		)
		(property "Value" ""
			(at 0 0 90)
			(layer "B.Fab")
			(effects
				(font
					(size 1.27 1.27)
				)
				(justify mirror)
			)
		)
		(duplicate_pad_numbers_are_jumpers no)
		(fp_line
			(start -0.299974 0.150114)
			(end 0.299974 0.150114)
			(stroke
				(width 0.1)
				(type default)
			)
			(layer "B.Fab")
		)
		(fp_line
			(start 0.299974 0.150114)
			(end 0.299974 -0.150114)
			(stroke
				(width 0.1)
				(type default)
			)
			(layer "B.Fab")
		)
		(fp_line
			(start -0.299974 -0.150114)
			(end -0.299974 0.150114)
			(stroke
				(width 0.1)
				(type default)
			)
			(layer "B.Fab")
		)
		(fp_line
			(start 0.299974 -0.150114)
			(end -0.299974 -0.150114)
			(stroke
				(width 0.1)
				(type default)
			)
			(layer "B.Fab")
		)
		(pad "1" smd rect
			(at 0.2667 0 90)
			(size 0.3048 0.381)
			(layers "B.Cu" "B.Mask" "B.Paste")
			(net "P1V25_SERDES_VDDPLL_PEX1")
		)
		(pad "2" smd rect
			(at -0.2667 0 90)
			(size 0.3048 0.381)
			(layers "B.Cu" "B.Mask" "B.Paste")
			(net "GND")
		)
	)
	(footprint ""
		(layer "B.Cu")
		(at 331.822298 -227.33127 -90)
		(property "Reference" "C2087"
			(at 0 0 90)
			(layer "B.SilkS")
			(hide yes)
			(effects
				(font
					(size 1.27 1.27)
				)
				(justify mirror)
			)
		)
		(property "Value" ""
			(at 0 0 90)
			(layer "B.Fab")
			(effects
				(font
					(size 1.27 1.27)
				)
				(justify mirror)
			)
		)
		(duplicate_pad_numbers_are_jumpers no)
		(fp_line
			(start -0.69215 0.2921)
			(end 0.69215 0.2921)
			(stroke
				(width 0.1524)
				(type default)
			)
			(layer "B.SilkS")
		)
		(fp_line
			(start 0.69215 0.2921)
			(end 0.69215 -0.2921)
			(stroke
				(width 0.1524)
				(type default)
			)
			(layer "B.SilkS")
		)
		(fp_line
			(start -0.69215 -0.2921)
			(end -0.69215 0.2921)
			(stroke
				(width 0.1524)
				(type default)
			)
			(layer "B.SilkS")
		)
		(fp_line
			(start 0.69215 -0.2921)
			(end -0.69215 -0.2921)
			(stroke
				(width 0.1524)
				(type default)
			)
			(layer "B.SilkS")
		)
		(fp_line
			(start -0.51435 0.2794)
			(end 0.51435 0.2794)
			(stroke
				(width 0.1)
				(type default)
			)
			(layer "B.Fab")
		)
		(fp_line
			(start 0.51435 0.2794)
			(end 0.51435 -0.2794)
			(stroke
				(width 0.1)
				(type default)
			)
			(layer "B.Fab")
		)
		(fp_line
			(start -0.51435 -0.2794)
			(end -0.51435 0.2794)
			(stroke
				(width 0.1)
				(type default)
			)
			(layer "B.Fab")
		)
		(fp_line
			(start 0.51435 -0.2794)
			(end -0.51435 -0.2794)
			(stroke
				(width 0.1)
				(type default)
			)
			(layer "B.Fab")
		)
		(pad "1" smd circle
			(at 0.40005 0 90)
			(size 0 0)
			(layers "B.Cu" "B.Mask" "B.Paste")
			(net "P3V3_FPGA_VCCIO5")
		)
		(pad "2" smd circle
			(at -0.40005 0 90)
			(size 0 0)
			(layers "B.Cu" "B.Mask" "B.Paste")
			(net "GND")
		)
		(zone
			(layer "B.Cu")
			(hatch none 0.5)
			(connect_pads
				(clearance 0)
			)
			(min_thickness 0.25)
			(keepout
				(tracks not_allowed)
				(vias allowed)
				(pads allowed)
				(copperpour not_allowed)
				(footprints allowed)
			)
			(placement
				(enabled no)
				(sheetname "")
			)
			(fill
				(thermal_gap 0.5)
				(thermal_bridge_width 0.5)
				(island_removal_mode 0)
			)
			(polygon
				(pts
					(xy 331.734668 -227.14077) (xy 331.676502 -227.23221) (xy 331.676502 -227.4316) (xy 331.734668 -227.52177)
					(xy 331.909928 -227.52177) (xy 331.968348 -227.4316) (xy 331.968348 -227.23221) (xy 331.910182 -227.14077)
				)
			)
		)
	)
	(footprint ""
		(layer "B.Cu")
		(at 349.679514 -214.381334 180)
		(property "Reference" "C2039"
			(at 0 0 0)
			(layer "B.SilkS")
			(hide yes)
			(effects
				(font
					(size 1.27 1.27)
				)
				(justify mirror)
			)
		)
		(property "Value" ""
			(at 0 0 0)
			(layer "B.Fab")
			(effects
				(font
					(size 1.27 1.27)
				)
				(justify mirror)
			)
		)
		(duplicate_pad_numbers_are_jumpers no)
		(fp_line
			(start 0.69215 0.2921)
			(end 0.69215 -0.2921)
			(stroke
				(width 0.1524)
				(type default)
			)
			(layer "B.SilkS")
		)
		(fp_line
			(start 0.69215 -0.2921)
			(end -0.69215 -0.2921)
			(stroke
				(width 0.1524)
				(type default)
			)
			(layer "B.SilkS")
		)
		(fp_line
			(start -0.69215 0.2921)
			(end 0.69215 0.2921)
			(stroke
				(width 0.1524)
				(type default)
			)
			(layer "B.SilkS")
		)
		(fp_line
			(start -0.69215 -0.2921)
			(end -0.69215 0.2921)
			(stroke
				(width 0.1524)
				(type default)
			)
			(layer "B.SilkS")
		)
		(fp_line
			(start 0.51435 0.2794)
			(end 0.51435 -0.2794)
			(stroke
				(width 0.1)
				(type default)
			)
			(layer "B.Fab")
		)
		(fp_line
			(start 0.51435 -0.2794)
			(end -0.51435 -0.2794)
			(stroke
				(width 0.1)
				(type default)
			)
			(layer "B.Fab")
		)
		(fp_line
			(start -0.51435 0.2794)
			(end 0.51435 0.2794)
			(stroke
				(width 0.1)
				(type default)
			)
			(layer "B.Fab")
		)
		(fp_line
			(start -0.51435 -0.2794)
			(end -0.51435 0.2794)
			(stroke
				(width 0.1)
				(type default)
			)
			(layer "B.Fab")
		)
		(pad "1" smd circle
			(at 0.40005 0)
			(size 0 0)
			(layers "B.Cu" "B.Mask" "B.Paste")
			(net "P3V3_FPGA_VCCIO1")
		)
		(pad "2" smd circle
			(at -0.40005 0)
			(size 0 0)
			(layers "B.Cu" "B.Mask" "B.Paste")
			(net "GND")
		)
		(zone
			(layer "B.Cu")
			(hatch none 0.5)
			(connect_pads
				(clearance 0)
			)
			(min_thickness 0.25)
			(keepout
				(tracks not_allowed)
				(vias allowed)
				(pads allowed)
				(copperpour not_allowed)
				(footprints allowed)
			)
			(placement
				(enabled no)
				(sheetname "")
			)
			(fill
				(thermal_gap 0.5)
				(thermal_bridge_width 0.5)
				(island_removal_mode 0)
			)
			(polygon
				(pts
					(xy 349.489014 -214.468964) (xy 349.580454 -214.52713) (xy 349.779844 -214.52713) (xy 349.870014 -214.468964)
					(xy 349.870014 -214.293704) (xy 349.779844 -214.235284) (xy 349.580454 -214.235284) (xy 349.489014 -214.29345)
				)
			)
		)
	)
	(footprint ""
		(layer "B.Cu")
		(at 105.287826 -319.545462 -90)
		(property "Reference" "L47"
			(at 0 0 90)
			(layer "B.SilkS")
			(hide yes)
			(effects
				(font
					(size 1.27 1.27)
				)
				(justify mirror)
			)
		)
		(property "Value" ""
			(at 0 0 90)
			(layer "B.Fab")
			(effects
				(font
					(size 1.27 1.27)
				)
				(justify mirror)
			)
		)
		(duplicate_pad_numbers_are_jumpers no)
		(fp_line
			(start -2.248154 4.9911)
			(end -2.248154 2.048002)
			(stroke
				(width 0.1524)
				(type default)
			)
			(layer "B.SilkS")
		)
		(fp_line
			(start 2.248154 4.9911)
			(end -2.248154 4.9911)
			(stroke
				(width 0.1524)
				(type default)
			)
			(layer "B.SilkS")
		)
		(fp_line
			(start 2.248154 2.048002)
			(end 2.248154 4.9911)
			(stroke
				(width 0.1524)
				(type default)
			)
			(layer "B.SilkS")
		)
		(fp_line
			(start -2.248154 -4.9911)
			(end 2.248154 -4.9911)
			(stroke
				(width 0.1524)
				(type default)
			)
			(layer "B.SilkS")
		)
		(fp_line
			(start 2.248154 -4.9911)
			(end 2.248154 -2.09804)
			(stroke
				(width 0.1524)
				(type default)
			)
			(layer "B.SilkS")
		)
		(fp_line
			(start -1.700022 0.899922)
			(end -1.700022 -0.899922)
			(stroke
				(width 0.1)
				(type default)
			)
			(layer "B.Fab")
		)
		(fp_line
			(start 1.700022 0.899922)
			(end -1.700022 0.899922)
			(stroke
				(width 0.1)
				(type default)
			)
			(layer "B.Fab")
		)
		(fp_line
			(start -1.700022 -0.899922)
			(end 1.700022 -0.899922)
			(stroke
				(width 0.1)
				(type default)
			)
			(layer "B.Fab")
		)
		(fp_line
			(start 1.700022 -0.899922)
			(end 1.700022 0.899922)
			(stroke
				(width 0.1)
				(type default)
			)
			(layer "B.Fab")
		)
		(pad "1" smd rect
			(at 1.575054 0 90)
			(size 1.1684 9.8044)
			(layers "B.Cu" "B.Mask" "B.Paste")
			(net "P0V8_PEX0")
		)
		(pad "2" smd rect
			(at -1.575054 0 90)
			(size 1.1684 9.8044)
			(layers "B.Cu" "B.Mask" "B.Paste")
			(net "P0V8_SERDES_VDDA_PEX0")
		)
	)
	(footprint ""
		(layer "B.Cu")
		(at 404.149814 -292.099746 90)
		(property "Reference" "C1984"
			(at 0 0 90)
			(layer "B.SilkS")
			(hide yes)
			(effects
				(font
					(size 1.27 1.27)
				)
				(justify mirror)
			)
		)
		(property "Value" ""
			(at 0 0 90)
			(layer "B.Fab")
			(effects
				(font
					(size 1.27 1.27)
				)
				(justify mirror)
			)
		)
		(duplicate_pad_numbers_are_jumpers no)
		(fp_line
			(start 0.299974 -0.150114)
			(end -0.299974 -0.150114)
			(stroke
				(width 0.1)
				(type default)
			)
			(layer "B.Fab")
		)
		(fp_line
			(start -0.299974 -0.150114)
			(end -0.299974 0.150114)
			(stroke
				(width 0.1)
				(type default)
			)
			(layer "B.Fab")
		)
		(fp_line
			(start 0.299974 0.150114)
			(end 0.299974 -0.150114)
			(stroke
				(width 0.1)
				(type default)
			)
			(layer "B.Fab")
		)
		(fp_line
			(start -0.299974 0.150114)
			(end 0.299974 0.150114)
			(stroke
				(width 0.1)
				(type default)
			)
			(layer "B.Fab")
		)
		(pad "1" smd rect
			(at 0.2667 0 270)
			(size 0.3048 0.381)
			(layers "B.Cu" "B.Mask" "B.Paste")
			(net "P0V8_SERDES_VDDA_PEX3")
		)
		(pad "2" smd rect
			(at -0.2667 0 270)
			(size 0.3048 0.381)
			(layers "B.Cu" "B.Mask" "B.Paste")
			(net "GND")
		)
	)
	(footprint ""
		(layer "B.Cu")
		(at 220.676978 -266.873228)
		(property "Reference" "R6133"
			(at 0 0 0)
			(layer "B.SilkS")
			(hide yes)
			(effects
				(font
					(size 1.27 1.27)
				)
				(justify mirror)
			)
		)
		(property "Value" ""
			(at 0 0 0)
			(layer "B.Fab")
			(effects
				(font
					(size 1.27 1.27)
				)
				(justify mirror)
			)
		)
		(duplicate_pad_numbers_are_jumpers no)
		(fp_line
			(start -2.576322 -1.1303)
			(end -2.576322 1.1303)
			(stroke
				(width 0.1524)
				(type default)
			)
			(layer "B.SilkS")
		)
		(fp_line
			(start -2.576322 1.1303)
			(end 2.576322 1.1303)
			(stroke
				(width 0.1524)
				(type default)
			)
			(layer "B.SilkS")
		)
		(fp_line
			(start 2.576322 -1.1303)
			(end -2.576322 -1.1303)
			(stroke
				(width 0.1524)
				(type default)
			)
			(layer "B.SilkS")
		)
		(fp_line
			(start 2.576322 1.1303)
			(end 2.576322 -1.1303)
			(stroke
				(width 0.1524)
				(type default)
			)
			(layer "B.SilkS")
		)
		(fp_line
			(start -1.649984 -0.899922)
			(end 1.649984 -0.899922)
			(stroke
				(width 0.1)
				(type default)
			)
			(layer "B.Fab")
		)
		(fp_line
			(start -1.649984 0.899922)
			(end -1.649984 -0.899922)
			(stroke
				(width 0.1)
				(type default)
			)
			(layer "B.Fab")
		)
		(fp_line
			(start 1.649984 -0.899922)
			(end 1.649984 0.899922)
			(stroke
				(width 0.1)
				(type default)
			)
			(layer "B.Fab")
		)
		(fp_line
			(start 1.649984 0.899922)
			(end -1.649984 0.899922)
			(stroke
				(width 0.1)
				(type default)
			)
			(layer "B.Fab")
		)
		(pad "1A" smd rect
			(at 1.700022 0 180)
			(size 1.4986 2.0066)
			(layers "B.Cu" "B.Mask" "B.Paste")
			(net "P1V25_PEX1")
		)
		(pad "1B" smd rect
			(at 1.077722 0 180)
			(size 0.254 0.508)
			(layers "B.Cu" "B.Mask" "B.Paste")
			(net "P1V25_PEX1")
		)
		(pad "2A" smd rect
			(at -1.700022 0 180)
			(size 1.4986 2.0066)
			(layers "B.Cu" "B.Mask" "B.Paste")
			(net "P1V25_SERDES_VDDPLL_PEX1")
		)
		(pad "2B" smd rect
			(at -1.077722 0 180)
			(size 0.254 0.508)
			(layers "B.Cu" "B.Mask" "B.Paste")
			(net "P1V25_SERDES_VDDPLL_PEX1")
		)
	)
	(footprint ""
		(layer "B.Cu")
		(at 176.699926 -292.099746 90)
		(property "Reference" "C1478"
			(at 0 0 90)
			(layer "B.SilkS")
			(hide yes)
			(effects
				(font
					(size 1.27 1.27)
				)
				(justify mirror)
			)
		)
		(property "Value" ""
			(at 0 0 90)
			(layer "B.Fab")
			(effects
				(font
					(size 1.27 1.27)
				)
				(justify mirror)
			)
		)
		(duplicate_pad_numbers_are_jumpers no)
		(fp_line
			(start 0.299974 -0.150114)
			(end -0.299974 -0.150114)
			(stroke
				(width 0.1)
				(type default)
			)
			(layer "B.Fab")
		)
		(fp_line
			(start -0.299974 -0.150114)
			(end -0.299974 0.150114)
			(stroke
				(width 0.1)
				(type default)
			)
			(layer "B.Fab")
		)
		(fp_line
			(start 0.299974 0.150114)
			(end 0.299974 -0.150114)
			(stroke
				(width 0.1)
				(type default)
			)
			(layer "B.Fab")
		)
		(fp_line
			(start -0.299974 0.150114)
			(end 0.299974 0.150114)
			(stroke
				(width 0.1)
				(type default)
			)
			(layer "B.Fab")
		)
		(pad "1" smd rect
			(at 0.2667 0 270)
			(size 0.3048 0.381)
			(layers "B.Cu" "B.Mask" "B.Paste")
			(net "P0V8_SERDES_VDDA_PEX1")
		)
		(pad "2" smd rect
			(at -0.2667 0 270)
			(size 0.3048 0.381)
			(layers "B.Cu" "B.Mask" "B.Paste")
			(net "GND")
		)
	)
	(footprint ""
		(layer "B.Cu")
		(at 238.938054 -278.872442 -90)
		(property "Reference" "C4332"
			(at 0 0 90)
			(layer "B.SilkS")
			(hide yes)
			(effects
				(font
					(size 1.27 1.27)
				)
				(justify mirror)
			)
		)
		(property "Value" ""
			(at 0 0 90)
			(layer "B.Fab")
			(effects
				(font
					(size 1.27 1.27)
				)
				(justify mirror)
			)
		)
		(duplicate_pad_numbers_are_jumpers no)
		(fp_line
			(start -1.2954 0.5842)
			(end 1.2954 0.5842)
			(stroke
				(width 0.1524)
				(type default)
			)
			(layer "B.SilkS")
		)
		(fp_line
			(start 1.2954 0.5842)
			(end 1.2954 -0.5842)
			(stroke
				(width 0.1524)
				(type default)
			)
			(layer "B.SilkS")
		)
		(fp_line
			(start -1.2954 -0.5842)
			(end -1.2954 0.5842)
			(stroke
				(width 0.1524)
				(type default)
			)
			(layer "B.SilkS")
		)
		(fp_line
			(start 1.2954 -0.5842)
			(end -1.2954 -0.5842)
			(stroke
				(width 0.1524)
				(type default)
			)
			(layer "B.SilkS")
		)
		(fp_line
			(start -0.8636 0.4572)
			(end 0.8636 0.4572)
			(stroke
				(width 0.1)
				(type default)
			)
			(layer "B.Fab")
		)
		(fp_line
			(start 0.8636 0.4572)
			(end 0.8636 0.4064)
			(stroke
				(width 0.1)
				(type default)
			)
			(layer "B.Fab")
		)
		(fp_line
			(start -1.1938 0.4064)
			(end -0.8636 0.4064)
			(stroke
				(width 0.1)
				(type default)
			)
			(layer "B.Fab")
		)
		(fp_line
			(start -0.8636 0.4064)
			(end -0.8636 0.4572)
			(stroke
				(width 0.1)
				(type default)
			)
			(layer "B.Fab")
		)
		(fp_line
			(start 0.8636 0.4064)
			(end 1.1938 0.4064)
			(stroke
				(width 0.1)
				(type default)
			)
			(layer "B.Fab")
		)
		(fp_line
			(start 1.1938 0.4064)
			(end 1.1938 -0.4064)
			(stroke
				(width 0.1)
				(type default)
			)
			(layer "B.Fab")
		)
		(fp_line
			(start -1.1938 -0.4064)
			(end -1.1938 0.4064)
			(stroke
				(width 0.1)
				(type default)
			)
			(layer "B.Fab")
		)
		(fp_line
			(start -0.8636 -0.4064)
			(end -1.1938 -0.4064)
			(stroke
				(width 0.1)
				(type default)
			)
			(layer "B.Fab")
		)
		(fp_line
			(start 0.8636 -0.4064)
			(end 0.8636 -0.4572)
			(stroke
				(width 0.1)
				(type default)
			)
			(layer "B.Fab")
		)
		(fp_line
			(start 1.1938 -0.4064)
			(end 0.8636 -0.4064)
			(stroke
				(width 0.1)
				(type default)
			)
			(layer "B.Fab")
		)
		(fp_line
			(start -0.8636 -0.4572)
			(end -0.8636 -0.4064)
			(stroke
				(width 0.1)
				(type default)
			)
			(layer "B.Fab")
		)
		(fp_line
			(start 0.8636 -0.4572)
			(end -0.8636 -0.4572)
			(stroke
				(width 0.1)
				(type default)
			)
			(layer "B.Fab")
		)
		(pad "1" smd rect
			(at 0.7366 0 180)
			(size 0.7112 0.8128)
			(layers "B.Cu" "B.Mask" "B.Paste")
			(net "P1V25_PEX2")
		)
		(pad "2" smd rect
			(at -0.7366 0 180)
			(size 0.7112 0.8128)
			(layers "B.Cu" "B.Mask" "B.Paste")
			(net "GND")
		)
	)
)
